(kicad_pcb
	(version 20260206)
	(generator "pcbnew")
	(generator_version "10.0")
	(general
		(thickness 1.6)
		(legacy_teardrops no)
	)
	(paper "A4")
	(title_block
		(title "01162023_DA0F0TEBIF0_F0T_Expander_BD_F_brd_V02_OCP.brd")
		(comment 1 "Grand Teton / footprints 1439-1445 of 9728")
	)
	(layers
		(0 "F.Cu" signal "TOP")
		(4 "In1.Cu" signal "GND")
		(6 "In2.Cu" signal "VCC")
		(8 "In3.Cu" signal "VCC1")
		(10 "In4.Cu" signal "GND1")
		(12 "In5.Cu" signal "IN1")
		(14 "In6.Cu" signal "GND2")
		(16 "In7.Cu" signal "IN2")
		(18 "In8.Cu" signal "GND3")
		(20 "In9.Cu" signal "IN3")
		(22 "In10.Cu" signal "GND4")
		(24 "In11.Cu" signal "IN4")
		(26 "In12.Cu" signal "GND5")
		(28 "In13.Cu" signal "IN5")
		(30 "In14.Cu" signal "GND6")
		(32 "In15.Cu" signal "IN6")
		(34 "In16.Cu" signal "GND7")
		(2 "B.Cu" signal "BOTTOM")
		(9 "F.Adhes" user "F.Adhesive")
		(11 "B.Adhes" user "B.Adhesive")
		(13 "F.Paste" user "Package Geometry/Pastemask Top")
		(15 "B.Paste" user "Package Geometry/Pastemask Bottom")
		(5 "F.SilkS" user "Ref Des/Silkscreen Top")
		(7 "B.SilkS" user "Ref Des/Silkscreen Bottom")
		(1 "F.Mask" user "Board Geometry/Soldermask Top")
		(3 "B.Mask" user "Board Geometry/Soldermask Bottom")
		(17 "Dwgs.User" user "User.Drawings")
		(19 "Cmts.User" user "User.Comments")
		(21 "Eco1.User" user "User.Eco1")
		(23 "Eco2.User" user "User.Eco2")
		(25 "Edge.Cuts" user "Board Geometry/Outline")
		(27 "Margin" user)
		(31 "F.CrtYd" user "Package Geometry/Place Bound Top")
		(29 "B.CrtYd" user "Package Geometry/Place Bound Bottom")
		(35 "F.Fab" user "Ref Des/Assembly Top")
		(33 "B.Fab" user "Ref Des/Assembly Bottom")
	)
	(footprint ""
		(layer "F.Cu")
		(at 385.304792 -140.85697 180)
		(property "Reference" "R339"
			(at 0 0 180)
			(layer "F.SilkS")
			(hide yes)
			(effects
				(font
					(size 1.27 1.27)
				)
			)
		)
		(property "Value" ""
			(at 0 0 180)
			(layer "F.Fab")
			(effects
				(font
					(size 1.27 1.27)
				)
			)
		)
		(duplicate_pad_numbers_are_jumpers no)
		(fp_line
			(start 0.7874 0.4064)
			(end -0.7874 0.4064)
			(stroke
				(width 0.1524)
				(type default)
			)
			(layer "F.SilkS")
		)
		(fp_line
			(start 0.7874 -0.4064)
			(end 0.7874 0.4064)
			(stroke
				(width 0.1524)
				(type default)
			)
			(layer "F.SilkS")
		)
		(fp_line
			(start -0.7874 0.4064)
			(end -0.7874 -0.4064)
			(stroke
				(width 0.1524)
				(type default)
			)
			(layer "F.SilkS")
		)
		(fp_line
			(start -0.7874 -0.4064)
			(end 0.7874 -0.4064)
			(stroke
				(width 0.1524)
				(type default)
			)
			(layer "F.SilkS")
		)
		(fp_line
			(start 0.67945 0.3048)
			(end 0.120396 0.3048)
			(stroke
				(width 0.1)
				(type default)
			)
			(layer "F.Fab")
		)
		(fp_line
			(start 0.67945 -0.3048)
			(end 0.67945 0.3048)
			(stroke
				(width 0.1)
				(type default)
			)
			(layer "F.Fab")
		)
		(fp_line
			(start 0.12065 -0.2794)
			(end 0.12065 -0.3048)
			(stroke
				(width 0.1)
				(type default)
			)
			(layer "F.Fab")
		)
		(fp_line
			(start 0.12065 -0.3048)
			(end 0.67945 -0.3048)
			(stroke
				(width 0.1)
				(type default)
			)
			(layer "F.Fab")
		)
		(fp_line
			(start 0.120396 0.3048)
			(end 0.120396 0.2794)
			(stroke
				(width 0.1)
				(type default)
			)
			(layer "F.Fab")
		)
		(fp_line
			(start 0.120396 0.2794)
			(end -0.12065 0.2794)
			(stroke
				(width 0.1)
				(type default)
			)
			(layer "F.Fab")
		)
		(fp_line
			(start -0.12065 0.3048)
			(end -0.67945 0.3048)
			(stroke
				(width 0.1)
				(type default)
			)
			(layer "F.Fab")
		)
		(fp_line
			(start -0.12065 0.2794)
			(end -0.12065 0.3048)
			(stroke
				(width 0.1)
				(type default)
			)
			(layer "F.Fab")
		)
		(fp_line
			(start -0.12065 -0.2794)
			(end 0.12065 -0.2794)
			(stroke
				(width 0.1)
				(type default)
			)
			(layer "F.Fab")
		)
		(fp_line
			(start -0.12065 -0.305054)
			(end -0.12065 -0.2794)
			(stroke
				(width 0.1)
				(type default)
			)
			(layer "F.Fab")
		)
		(fp_line
			(start -0.67945 0.3048)
			(end -0.67945 -0.305054)
			(stroke
				(width 0.1)
				(type default)
			)
			(layer "F.Fab")
		)
		(fp_line
			(start -0.67945 -0.305054)
			(end -0.12065 -0.305054)
			(stroke
				(width 0.1)
				(type default)
			)
			(layer "F.Fab")
		)
		(pad "1" smd circle
			(at -0.40005 0 180)
			(size 0 0)
			(layers "F.Cu" "F.Mask" "F.Paste")
			(net "NIC6_BIF2_N")
		)
		(pad "2" smd circle
			(at 0.40005 0 180)
			(size 0 0)
			(layers "F.Cu" "F.Mask" "F.Paste")
			(net "P3V3_AUX")
		)
	)
	(footprint ""
		(layer "F.Cu")
		(at 94.467426 -112.903508 90)
		(property "Reference" "PC606"
			(at 0 0 90)
			(layer "F.SilkS")
			(hide yes)
			(effects
				(font
					(size 1.27 1.27)
				)
			)
		)
		(property "Value" ""
			(at 0 0 90)
			(layer "F.Fab")
			(effects
				(font
					(size 1.27 1.27)
				)
			)
		)
		(duplicate_pad_numbers_are_jumpers no)
		(fp_line
			(start 1.524 -0.762)
			(end 1.524 0.762)
			(stroke
				(width 0.1524)
				(type default)
			)
			(layer "F.SilkS")
		)
		(fp_line
			(start -1.524 -0.762)
			(end 1.524 -0.762)
			(stroke
				(width 0.1524)
				(type default)
			)
			(layer "F.SilkS")
		)
		(fp_line
			(start 1.524 0.762)
			(end -1.524 0.762)
			(stroke
				(width 0.1524)
				(type default)
			)
			(layer "F.SilkS")
		)
		(fp_line
			(start -1.524 0.762)
			(end -1.524 -0.762)
			(stroke
				(width 0.1524)
				(type default)
			)
			(layer "F.SilkS")
		)
		(fp_line
			(start 1.1049 -0.724916)
			(end -1.1049 -0.724916)
			(stroke
				(width 0.1)
				(type default)
			)
			(layer "F.Fab")
		)
		(fp_line
			(start -1.1049 -0.724916)
			(end -1.1049 0.724916)
			(stroke
				(width 0.1)
				(type default)
			)
			(layer "F.Fab")
		)
		(fp_line
			(start 1.1049 0.724916)
			(end 1.1049 -0.724916)
			(stroke
				(width 0.1)
				(type default)
			)
			(layer "F.Fab")
		)
		(fp_line
			(start -1.1049 0.724916)
			(end 1.1049 0.724916)
			(stroke
				(width 0.1)
				(type default)
			)
			(layer "F.Fab")
		)
		(pad "1" smd rect
			(at -0.889 0 270)
			(size 1.016 1.27)
			(layers "F.Cu" "F.Mask" "F.Paste")
			(net "P12V_NIC1_R")
		)
		(pad "2" smd rect
			(at 0.889 0 270)
			(size 1.016 1.27)
			(layers "F.Cu" "F.Mask" "F.Paste")
			(net "GND")
		)
	)
	(footprint ""
		(layer "F.Cu")
		(at 161.75482 -22.867366 90)
		(property "Reference" "C3913"
			(at 0 0 90)
			(layer "F.SilkS")
			(hide yes)
			(effects
				(font
					(size 1.27 1.27)
				)
			)
		)
		(property "Value" ""
			(at 0 0 90)
			(layer "F.Fab")
			(effects
				(font
					(size 1.27 1.27)
				)
			)
		)
		(duplicate_pad_numbers_are_jumpers no)
		(fp_line
			(start 0.7874 -0.4064)
			(end 0.7874 0.4064)
			(stroke
				(width 0.1524)
				(type default)
			)
			(layer "F.SilkS")
		)
		(fp_line
			(start -0.7874 -0.4064)
			(end 0.7874 -0.4064)
			(stroke
				(width 0.1524)
				(type default)
			)
			(layer "F.SilkS")
		)
		(fp_line
			(start 0.7874 0.4064)
			(end -0.7874 0.4064)
			(stroke
				(width 0.1524)
				(type default)
			)
			(layer "F.SilkS")
		)
		(fp_line
			(start -0.7874 0.4064)
			(end -0.7874 -0.4064)
			(stroke
				(width 0.1524)
				(type default)
			)
			(layer "F.SilkS")
		)
		(fp_line
			(start -0.12065 -0.305054)
			(end -0.12065 -0.2794)
			(stroke
				(width 0.1)
				(type default)
			)
			(layer "F.Fab")
		)
		(fp_line
			(start -0.67945 -0.305054)
			(end -0.12065 -0.305054)
			(stroke
				(width 0.1)
				(type default)
			)
			(layer "F.Fab")
		)
		(fp_line
			(start 0.67945 -0.3048)
			(end 0.67945 0.3048)
			(stroke
				(width 0.1)
				(type default)
			)
			(layer "F.Fab")
		)
		(fp_line
			(start 0.12065 -0.3048)
			(end 0.67945 -0.3048)
			(stroke
				(width 0.1)
				(type default)
			)
			(layer "F.Fab")
		)
		(fp_line
			(start 0.12065 -0.2794)
			(end 0.12065 -0.3048)
			(stroke
				(width 0.1)
				(type default)
			)
			(layer "F.Fab")
		)
		(fp_line
			(start -0.12065 -0.2794)
			(end 0.12065 -0.2794)
			(stroke
				(width 0.1)
				(type default)
			)
			(layer "F.Fab")
		)
		(fp_line
			(start 0.120396 0.2794)
			(end -0.12065 0.2794)
			(stroke
				(width 0.1)
				(type default)
			)
			(layer "F.Fab")
		)
		(fp_line
			(start -0.12065 0.2794)
			(end -0.12065 0.3048)
			(stroke
				(width 0.1)
				(type default)
			)
			(layer "F.Fab")
		)
		(fp_line
			(start 0.67945 0.3048)
			(end 0.120396 0.3048)
			(stroke
				(width 0.1)
				(type default)
			)
			(layer "F.Fab")
		)
		(fp_line
			(start 0.120396 0.3048)
			(end 0.120396 0.2794)
			(stroke
				(width 0.1)
				(type default)
			)
			(layer "F.Fab")
		)
		(fp_line
			(start -0.12065 0.3048)
			(end -0.67945 0.3048)
			(stroke
				(width 0.1)
				(type default)
			)
			(layer "F.Fab")
		)
		(fp_line
			(start -0.67945 0.3048)
			(end -0.67945 -0.305054)
			(stroke
				(width 0.1)
				(type default)
			)
			(layer "F.Fab")
		)
		(pad "1" smd circle
			(at -0.40005 0 90)
			(size 0 0)
			(layers "F.Cu" "F.Mask" "F.Paste")
			(net "P12V_SSD5")
		)
		(pad "2" smd circle
			(at 0.40005 0 90)
			(size 0 0)
			(layers "F.Cu" "F.Mask" "F.Paste")
			(net "GND")
		)
	)
	(footprint ""
		(layer "F.Cu")
		(at 56.84774 -40.037258 90)
		(property "Reference" "U365"
			(at 0.094742 2.38633 90)
			(unlocked yes)
			(layer "F.SilkS")
			(effects
				(font
					(size 0.7874 0.5842)
					(thickness 0.1524)
				)
			)
		)
		(property "Value" ""
			(at 0 0 90)
			(layer "F.Fab")
			(effects
				(font
					(size 1.27 1.27)
				)
			)
		)
		(duplicate_pad_numbers_are_jumpers no)
		(fp_line
			(start -1.949958 -1.610106)
			(end 1.949958 -1.610106)
			(stroke
				(width 0.1524)
				(type default)
			)
			(layer "F.SilkS")
		)
		(fp_line
			(start 1.949958 -1.560068)
			(end 1.949958 1.610106)
			(stroke
				(width 0.1524)
				(type default)
			)
			(layer "F.SilkS")
		)
		(fp_line
			(start 1.949958 1.610106)
			(end -1.949958 1.610106)
			(stroke
				(width 0.1524)
				(type default)
			)
			(layer "F.SilkS")
		)
		(fp_line
			(start -1.949958 1.610106)
			(end -1.949958 -1.610106)
			(stroke
				(width 0.1524)
				(type default)
			)
			(layer "F.SilkS")
		)
		(fp_line
			(start 0.750062 -1.560068)
			(end 0.750062 1.560068)
			(stroke
				(width 0.1)
				(type default)
			)
			(layer "F.Fab")
		)
		(fp_line
			(start -0.750062 -1.560068)
			(end 0.750062 -1.560068)
			(stroke
				(width 0.1)
				(type default)
			)
			(layer "F.Fab")
		)
		(fp_line
			(start 0.750062 1.560068)
			(end -0.750062 1.560068)
			(stroke
				(width 0.1)
				(type default)
			)
			(layer "F.Fab")
		)
		(fp_line
			(start -0.750062 1.560068)
			(end -0.750062 -1.560068)
			(stroke
				(width 0.1)
				(type default)
			)
			(layer "F.Fab")
		)
		(pad "D" smd rect
			(at 1.100074 0)
			(size 1.016 1.4224)
			(layers "F.Cu" "F.Mask" "F.Paste")
			(net "SSD2_AUX_P3V3_EN")
		)
		(pad "G" smd rect
			(at -1.100074 -0.94996)
			(size 1.016 1.4224)
			(layers "F.Cu" "F.Mask" "F.Paste")
			(net "PRSNT_SSD2_R1_N")
		)
		(pad "S" smd rect
			(at -1.100074 0.94996)
			(size 1.016 1.4224)
			(layers "F.Cu" "F.Mask" "F.Paste")
			(net "GND")
		)
	)
	(footprint ""
		(layer "F.Cu")
		(at 104.243632 -47.92091)
		(property "Reference" "R537"
			(at 0 0 0)
			(layer "F.SilkS")
			(hide yes)
			(effects
				(font
					(size 1.27 1.27)
				)
			)
		)
		(property "Value" ""
			(at 0 0 0)
			(layer "F.Fab")
			(effects
				(font
					(size 1.27 1.27)
				)
			)
		)
		(duplicate_pad_numbers_are_jumpers no)
		(fp_line
			(start -0.7874 -0.4064)
			(end 0.7874 -0.4064)
			(stroke
				(width 0.1524)
				(type default)
			)
			(layer "F.SilkS")
		)
		(fp_line
			(start -0.7874 0.4064)
			(end -0.7874 -0.4064)
			(stroke
				(width 0.1524)
				(type default)
			)
			(layer "F.SilkS")
		)
		(fp_line
			(start 0.7874 -0.4064)
			(end 0.7874 0.4064)
			(stroke
				(width 0.1524)
				(type default)
			)
			(layer "F.SilkS")
		)
		(fp_line
			(start 0.7874 0.4064)
			(end -0.7874 0.4064)
			(stroke
				(width 0.1524)
				(type default)
			)
			(layer "F.SilkS")
		)
		(fp_line
			(start -0.67945 -0.305054)
			(end -0.12065 -0.305054)
			(stroke
				(width 0.1)
				(type default)
			)
			(layer "F.Fab")
		)
		(fp_line
			(start -0.67945 0.3048)
			(end -0.67945 -0.305054)
			(stroke
				(width 0.1)
				(type default)
			)
			(layer "F.Fab")
		)
		(fp_line
			(start -0.12065 -0.305054)
			(end -0.12065 -0.2794)
			(stroke
				(width 0.1)
				(type default)
			)
			(layer "F.Fab")
		)
		(fp_line
			(start -0.12065 -0.2794)
			(end 0.12065 -0.2794)
			(stroke
				(width 0.1)
				(type default)
			)
			(layer "F.Fab")
		)
		(fp_line
			(start -0.12065 0.2794)
			(end -0.12065 0.3048)
			(stroke
				(width 0.1)
				(type default)
			)
			(layer "F.Fab")
		)
		(fp_line
			(start -0.12065 0.3048)
			(end -0.67945 0.3048)
			(stroke
				(width 0.1)
				(type default)
			)
			(layer "F.Fab")
		)
		(fp_line
			(start 0.120396 0.2794)
			(end -0.12065 0.2794)
			(stroke
				(width 0.1)
				(type default)
			)
			(layer "F.Fab")
		)
		(fp_line
			(start 0.120396 0.3048)
			(end 0.120396 0.2794)
			(stroke
				(width 0.1)
				(type default)
			)
			(layer "F.Fab")
		)
		(fp_line
			(start 0.12065 -0.3048)
			(end 0.67945 -0.3048)
			(stroke
				(width 0.1)
				(type default)
			)
			(layer "F.Fab")
		)
		(fp_line
			(start 0.12065 -0.2794)
			(end 0.12065 -0.3048)
			(stroke
				(width 0.1)
				(type default)
			)
			(layer "F.Fab")
		)
		(fp_line
			(start 0.67945 -0.3048)
			(end 0.67945 0.3048)
			(stroke
				(width 0.1)
				(type default)
			)
			(layer "F.Fab")
		)
		(fp_line
			(start 0.67945 0.3048)
			(end 0.120396 0.3048)
			(stroke
				(width 0.1)
				(type default)
			)
			(layer "F.Fab")
		)
		(pad "1" smd circle
			(at -0.40005 0)
			(size 0 0)
			(layers "F.Cu" "F.Mask" "F.Paste")
			(net "P3V3_AUX")
		)
		(pad "2" smd circle
			(at 0.40005 0)
			(size 0 0)
			(layers "F.Cu" "F.Mask" "F.Paste")
			(net "SSD_0_7_ADC_ALERT_N")
		)
	)
	(footprint ""
		(layer "F.Cu")
		(at 329.922886 -207.541368 -90)
		(property "Reference" "R4405"
			(at 0 0 270)
			(layer "F.SilkS")
			(hide yes)
			(effects
				(font
					(size 1.27 1.27)
				)
			)
		)
		(property "Value" ""
			(at 0 0 270)
			(layer "F.Fab")
			(effects
				(font
					(size 1.27 1.27)
				)
			)
		)
		(duplicate_pad_numbers_are_jumpers no)
		(fp_line
			(start -0.7874 0.4064)
			(end -0.7874 -0.4064)
			(stroke
				(width 0.1524)
				(type default)
			)
			(layer "F.SilkS")
		)
		(fp_line
			(start 0.7874 0.4064)
			(end -0.7874 0.4064)
			(stroke
				(width 0.1524)
				(type default)
			)
			(layer "F.SilkS")
		)
		(fp_line
			(start -0.7874 -0.4064)
			(end 0.7874 -0.4064)
			(stroke
				(width 0.1524)
				(type default)
			)
			(layer "F.SilkS")
		)
		(fp_line
			(start 0.7874 -0.4064)
			(end 0.7874 0.4064)
			(stroke
				(width 0.1524)
				(type default)
			)
			(layer "F.SilkS")
		)
		(fp_line
			(start -0.67945 0.3048)
			(end -0.67945 -0.305054)
			(stroke
				(width 0.1)
				(type default)
			)
			(layer "F.Fab")
		)
		(fp_line
			(start -0.12065 0.3048)
			(end -0.67945 0.3048)
			(stroke
				(width 0.1)
				(type default)
			)
			(layer "F.Fab")
		)
		(fp_line
			(start 0.120396 0.3048)
			(end 0.120396 0.2794)
			(stroke
				(width 0.1)
				(type default)
			)
			(layer "F.Fab")
		)
		(fp_line
			(start 0.67945 0.3048)
			(end 0.120396 0.3048)
			(stroke
				(width 0.1)
				(type default)
			)
			(layer "F.Fab")
		)
		(fp_line
			(start -0.12065 0.2794)
			(end -0.12065 0.3048)
			(stroke
				(width 0.1)
				(type default)
			)
			(layer "F.Fab")
		)
		(fp_line
			(start 0.120396 0.2794)
			(end -0.12065 0.2794)
			(stroke
				(width 0.1)
				(type default)
			)
			(layer "F.Fab")
		)
		(fp_line
			(start -0.12065 -0.2794)
			(end 0.12065 -0.2794)
			(stroke
				(width 0.1)
				(type default)
			)
			(layer "F.Fab")
		)
		(fp_line
			(start 0.12065 -0.2794)
			(end 0.12065 -0.3048)
			(stroke
				(width 0.1)
				(type default)
			)
			(layer "F.Fab")
		)
		(fp_line
			(start 0.12065 -0.3048)
			(end 0.67945 -0.3048)
			(stroke
				(width 0.1)
				(type default)
			)
			(layer "F.Fab")
		)
		(fp_line
			(start 0.67945 -0.3048)
			(end 0.67945 0.3048)
			(stroke
				(width 0.1)
				(type default)
			)
			(layer "F.Fab")
		)
		(fp_line
			(start -0.67945 -0.305054)
			(end -0.12065 -0.305054)
			(stroke
				(width 0.1)
				(type default)
			)
			(layer "F.Fab")
		)
		(fp_line
			(start -0.12065 -0.305054)
			(end -0.12065 -0.2794)
			(stroke
				(width 0.1)
				(type default)
			)
			(layer "F.Fab")
		)
		(pad "1" smd circle
			(at -0.40005 0 270)
			(size 0 0)
			(layers "F.Cu" "F.Mask" "F.Paste")
			(net "CLK_25M_FPGA_R")
		)
		(pad "2" smd circle
			(at 0.40005 0 270)
			(size 0 0)
			(layers "F.Cu" "F.Mask" "F.Paste")
			(net "CLK_25M_FPGA")
		)
	)
	(footprint ""
		(layer "F.Cu")
		(at 195.414646 -79.58201 90)
		(property "Reference" "R202"
			(at 0 0 90)
			(layer "F.SilkS")
			(hide yes)
			(effects
				(font
					(size 1.27 1.27)
				)
			)
		)
		(property "Value" ""
			(at 0 0 90)
			(layer "F.Fab")
			(effects
				(font
					(size 1.27 1.27)
				)
			)
		)
		(duplicate_pad_numbers_are_jumpers no)
		(fp_line
			(start 0.7874 -0.4064)
			(end 0.7874 0.4064)
			(stroke
				(width 0.1524)
				(type default)
			)
			(layer "F.SilkS")
		)
		(fp_line
			(start -0.7874 -0.4064)
			(end 0.7874 -0.4064)
			(stroke
				(width 0.1524)
				(type default)
			)
			(layer "F.SilkS")
		)
		(fp_line
			(start 0.7874 0.4064)
			(end -0.7874 0.4064)
			(stroke
				(width 0.1524)
				(type default)
			)
			(layer "F.SilkS")
		)
		(fp_line
			(start -0.7874 0.4064)
			(end -0.7874 -0.4064)
			(stroke
				(width 0.1524)
				(type default)
			)
			(layer "F.SilkS")
		)
		(fp_line
			(start -0.12065 -0.305054)
			(end -0.12065 -0.2794)
			(stroke
				(width 0.1)
				(type default)
			)
			(layer "F.Fab")
		)
		(fp_line
			(start -0.67945 -0.305054)
			(end -0.12065 -0.305054)
			(stroke
				(width 0.1)
				(type default)
			)
			(layer "F.Fab")
		)
		(fp_line
			(start 0.67945 -0.3048)
			(end 0.67945 0.3048)
			(stroke
				(width 0.1)
				(type default)
			)
			(layer "F.Fab")
		)
		(fp_line
			(start 0.12065 -0.3048)
			(end 0.67945 -0.3048)
			(stroke
				(width 0.1)
				(type default)
			)
			(layer "F.Fab")
		)
		(fp_line
			(start 0.12065 -0.2794)
			(end 0.12065 -0.3048)
			(stroke
				(width 0.1)
				(type default)
			)
			(layer "F.Fab")
		)
		(fp_line
			(start -0.12065 -0.2794)
			(end 0.12065 -0.2794)
			(stroke
				(width 0.1)
				(type default)
			)
			(layer "F.Fab")
		)
		(fp_line
			(start 0.120396 0.2794)
			(end -0.12065 0.2794)
			(stroke
				(width 0.1)
				(type default)
			)
			(layer "F.Fab")
		)
		(fp_line
			(start -0.12065 0.2794)
			(end -0.12065 0.3048)
			(stroke
				(width 0.1)
				(type default)
			)
			(layer "F.Fab")
		)
		(fp_line
			(start 0.67945 0.3048)
			(end 0.120396 0.3048)
			(stroke
				(width 0.1)
				(type default)
			)
			(layer "F.Fab")
		)
		(fp_line
			(start 0.120396 0.3048)
			(end 0.120396 0.2794)
			(stroke
				(width 0.1)
				(type default)
			)
			(layer "F.Fab")
		)
		(fp_line
			(start -0.12065 0.3048)
			(end -0.67945 0.3048)
			(stroke
				(width 0.1)
				(type default)
			)
			(layer "F.Fab")
		)
		(fp_line
			(start -0.67945 0.3048)
			(end -0.67945 -0.305054)
			(stroke
				(width 0.1)
				(type default)
			)
			(layer "F.Fab")
		)
		(pad "1" smd circle
			(at -0.40005 0 90)
			(size 0 0)
			(layers "F.Cu" "F.Mask" "F.Paste")
			(net "P3V3_NIC3")
		)
		(pad "2" smd circle
			(at 0.40005 0 90)
			(size 0 0)
			(layers "F.Cu" "F.Mask" "F.Paste")
			(net "HP_NIC3_PWRGD")
		)
	)
)
